(kicad_pcb
	(version 20260206)
	(generator "pcbnew")
	(generator_version "10.0")
	(general
		(thickness 1.6)
		(legacy_teardrops no)
	)
	(paper "A4")
	(title_block
		(title "baseboard — 13948-1b.1110WZS1818.brd")
		(comment 1 "Honey Badger (Wiwynn) / footprint 1534 of 2523 (CN8), pads 76-150 of 166")
	)
	(layers
		(0 "F.Cu" signal "TOP")
		(4 "In1.Cu" signal "L2GND")
		(6 "In2.Cu" signal "L3")
		(8 "In3.Cu" signal "L4VCC")
		(10 "In4.Cu" signal "L5VCC")
		(12 "In5.Cu" signal "L6")
		(14 "In6.Cu" signal "L7GND")
		(2 "B.Cu" signal "BOTTOM")
		(9 "F.Adhes" user "F.Adhesive")
		(11 "B.Adhes" user "B.Adhesive")
		(13 "F.Paste" user "Package Geometry/Pastemask Top")
		(15 "B.Paste" user "Package Geometry/Pastemask Bottom")
		(5 "F.SilkS" user "Ref Des/Silkscreen Top")
		(7 "B.SilkS" user "Ref Des/Silkscreen Bottom")
		(1 "F.Mask" user "Board Geometry/Soldermask Top")
		(3 "B.Mask" user "Board Geometry/Soldermask Bottom")
		(17 "Dwgs.User" user "User.Drawings")
		(19 "Cmts.User" user "User.Comments")
		(21 "Eco1.User" user "User.Eco1")
		(23 "Eco2.User" user "User.Eco2")
		(25 "Edge.Cuts" user "Board Geometry/Outline")
		(27 "Margin" user)
		(31 "F.CrtYd" user "Package Geometry/Place Bound Top")
		(29 "B.CrtYd" user "Package Geometry/Place Bound Bottom")
		(35 "F.Fab" user "Ref Des/Assembly Top")
		(33 "B.Fab" user "Ref Des/Assembly Bottom")
	)
	(footprint ""
		(layer "F.Cu")
		(at 209.799936 -77.0001 180)
		(property "Reference" "CN8"
			(at 0 0 180)
			(layer "F.SilkS")
			(hide yes)
			(effects
				(font
					(size 1.27 1.27)
				)
			)
		)
		(property "Value" "PCISLT164-44-GP"
			(at -23.3172 -6.8961 180)
			(unlocked yes)
			(layer "F.Fab")
			(hide yes)
			(effects
				(font
					(size 1.016 1.016)
					(thickness 0.1524)
				)
			)
		)
		(property "Device Type" "AAA-PCI-066-K06"
			(at -23.3172 -8.4201 180)
			(unlocked yes)
			(layer "F.Fab")
			(hide yes)
			(effects
				(font
					(size 1.016 1.016)
					(thickness 0.1524)
				)
			)
		)
		(duplicate_pad_numbers_are_jumpers no)
		(pad "A74" thru_hole circle
			(at 63.35014 -3.24993 180)
			(size 1.0922 1.0922)
			(drill 0.7366)
			(layers "*.Cu" "*.Mask")
			(remove_unused_layers no)
			(net "PCIE_10G_CPU_RX2_N")
			(clearance 0.1778)
			(thermal_gap 0.1778)
		)
		(pad "A75" thru_hole circle
			(at 64.34963 -1.24968 180)
			(size 1.0922 1.0922)
			(drill 0.7366)
			(layers "*.Cu" "*.Mask")
			(remove_unused_layers no)
			(net "GND")
			(clearance 0.1778)
			(thermal_gap 0.1778)
		)
		(pad "A76" thru_hole circle
			(at 65.35039 -3.24993 180)
			(size 1.0922 1.0922)
			(drill 0.7366)
			(layers "*.Cu" "*.Mask")
			(remove_unused_layers no)
			(net "GND")
			(clearance 0.1778)
			(thermal_gap 0.1778)
		)
		(pad "A77" thru_hole circle
			(at 66.34988 -1.24968 180)
			(size 1.0922 1.0922)
			(drill 0.7366)
			(layers "*.Cu" "*.Mask")
			(remove_unused_layers no)
			(net "PCIE_10G_CPU_RX3_P")
			(clearance 0.1778)
			(thermal_gap 0.1778)
		)
		(pad "A78" thru_hole circle
			(at 67.34937 -3.24993 180)
			(size 1.0922 1.0922)
			(drill 0.7366)
			(layers "*.Cu" "*.Mask")
			(remove_unused_layers no)
			(net "PCIE_10G_CPU_RX3_N")
			(clearance 0.1778)
			(thermal_gap 0.1778)
		)
		(pad "A79" thru_hole circle
			(at 68.35013 -1.24968 180)
			(size 1.0922 1.0922)
			(drill 0.7366)
			(layers "*.Cu" "*.Mask")
			(remove_unused_layers no)
			(net "GND")
			(clearance 0.1778)
			(thermal_gap 0.1778)
		)
		(pad "A80" thru_hole circle
			(at 69.34962 -3.24993 180)
			(size 1.0922 1.0922)
			(drill 0.7366)
			(layers "*.Cu" "*.Mask")
			(remove_unused_layers no)
			(net "GND")
			(clearance 0.1778)
			(thermal_gap 0.1778)
		)
		(pad "A81" thru_hole circle
			(at 70.35038 -1.24968 180)
			(size 1.0922 1.0922)
			(drill 0.7366)
			(layers "*.Cu" "*.Mask")
			(remove_unused_layers no)
			(net "P12V_MSB")
			(clearance 0.1778)
			(thermal_gap 0.1778)
		)
		(pad "A82" thru_hole circle
			(at 71.34987 -3.24993 180)
			(size 1.0922 1.0922)
			(drill 0.7366)
			(layers "*.Cu" "*.Mask")
			(remove_unused_layers no)
			(net "P12V_MSB")
			(clearance 0.1778)
			(thermal_gap 0.1778)
		)
		(pad "B1" thru_hole circle
			(at -11.64971 1.24968 180)
			(size 1.0922 1.0922)
			(drill 0.7366)
			(layers "*.Cu" "*.Mask")
			(remove_unused_layers no)
			(net "P12V_MSB")
			(clearance 0.1778)
			(thermal_gap 0.1778)
		)
		(pad "B2" thru_hole circle
			(at -10.65022 3.24993 180)
			(size 1.0922 1.0922)
			(drill 0.7366)
			(layers "*.Cu" "*.Mask")
			(remove_unused_layers no)
			(net "P12V_MSB")
			(clearance 0.1778)
			(thermal_gap 0.1778)
		)
		(pad "B3" thru_hole circle
			(at -9.64946 1.24968 180)
			(size 1.0922 1.0922)
			(drill 0.7366)
			(layers "*.Cu" "*.Mask")
			(remove_unused_layers no)
			(net "P12V_MSB")
			(clearance 0.1778)
			(thermal_gap 0.1778)
		)
		(pad "B4" thru_hole circle
			(at -8.64997 3.24993 180)
			(size 1.0922 1.0922)
			(drill 0.7366)
			(layers "*.Cu" "*.Mask")
			(remove_unused_layers no)
			(net "GND")
			(clearance 0.1778)
			(thermal_gap 0.1778)
		)
		(pad "B5" thru_hole circle
			(at -7.65048 1.24968 180)
			(size 1.0922 1.0922)
			(drill 0.7366)
			(layers "*.Cu" "*.Mask")
			(remove_unused_layers no)
			(net "BMC_MBC_I2C_E_SCL")
			(clearance 0.1778)
			(thermal_gap 0.1778)
		)
		(pad "B6" thru_hole circle
			(at -6.64972 3.24993 180)
			(size 1.0922 1.0922)
			(drill 0.7366)
			(layers "*.Cu" "*.Mask")
			(remove_unused_layers no)
			(net "BMC_MBC_I2C_E_SDA")
			(clearance 0.1778)
			(thermal_gap 0.1778)
		)
		(pad "B7" thru_hole circle
			(at -5.65023 1.24968 180)
			(size 1.0922 1.0922)
			(drill 0.7366)
			(layers "*.Cu" "*.Mask")
			(remove_unused_layers no)
			(net "GND")
			(clearance 0.1778)
			(thermal_gap 0.1778)
		)
		(pad "B8" thru_hole circle
			(at -4.64947 3.24993 180)
			(size 1.0922 1.0922)
			(drill 0.7366)
			(layers "*.Cu" "*.Mask")
			(remove_unused_layers no)
			(net "PMU_PWRBTN_N")
			(clearance 0.1778)
			(thermal_gap 0.1778)
		)
		(pad "B9" thru_hole circle
			(at -3.64998 1.24968 180)
			(size 1.0922 1.0922)
			(drill 0.7366)
			(layers "*.Cu" "*.Mask")
			(remove_unused_layers no)
			(net "USB_P0_DP")
			(clearance 0.1778)
			(thermal_gap 0.1778)
		)
		(pad "B10" thru_hole circle
			(at -2.65049 3.24993 180)
			(size 1.0922 1.0922)
			(drill 0.7366)
			(layers "*.Cu" "*.Mask")
			(remove_unused_layers no)
			(net "USB_P0_DN")
			(clearance 0.1778)
			(thermal_gap 0.1778)
		)
		(pad "B11" thru_hole circle
			(at -1.64973 1.24968 180)
			(size 1.0922 1.0922)
			(drill 0.7366)
			(layers "*.Cu" "*.Mask")
			(remove_unused_layers no)
			(net "CPU_RESET_N_R")
			(clearance 0.1778)
			(thermal_gap 0.1778)
		)
		(pad "B12" thru_hole circle
			(at 1.35001 3.24993 180)
			(size 1.0922 1.0922)
			(drill 0.7366)
			(layers "*.Cu" "*.Mask")
			(remove_unused_layers no)
			(net "BMC_MSB_I2C_E_ALERT_#")
			(clearance 0.1778)
			(thermal_gap 0.1778)
		)
		(pad "B13" thru_hole circle
			(at 2.3495 1.24968 180)
			(size 1.0922 1.0922)
			(drill 0.7366)
			(layers "*.Cu" "*.Mask")
			(remove_unused_layers no)
			(net "GND")
			(clearance 0.1778)
			(thermal_gap 0.1778)
		)
		(pad "B14" thru_hole circle
			(at 3.35026 3.24993 180)
			(size 1.0922 1.0922)
			(drill 0.7366)
			(layers "*.Cu" "*.Mask")
			(remove_unused_layers no)
			(net "GND")
			(clearance 0.1778)
			(thermal_gap 0.1778)
		)
		(pad "B15" thru_hole circle
			(at 4.34975 1.24968 180)
			(size 1.0922 1.0922)
			(drill 0.7366)
			(layers "*.Cu" "*.Mask")
			(remove_unused_layers no)
			(net "PCIE_SAS_CPU_TX_P0")
			(clearance 0.1778)
			(thermal_gap 0.1778)
		)
		(pad "B16" thru_hole circle
			(at 5.35051 3.24993 180)
			(size 1.0922 1.0922)
			(drill 0.7366)
			(layers "*.Cu" "*.Mask")
			(remove_unused_layers no)
			(net "PCIE_SAS_CPU_TX_N0")
			(clearance 0.1778)
			(thermal_gap 0.1778)
		)
		(pad "B17" thru_hole circle
			(at 6.35 1.24968 180)
			(size 1.0922 1.0922)
			(drill 0.7366)
			(layers "*.Cu" "*.Mask")
			(remove_unused_layers no)
			(net "GND")
			(clearance 0.1778)
			(thermal_gap 0.1778)
		)
		(pad "B18" thru_hole circle
			(at 7.34949 3.24993 180)
			(size 1.0922 1.0922)
			(drill 0.7366)
			(layers "*.Cu" "*.Mask")
			(remove_unused_layers no)
			(net "GND")
			(clearance 0.1778)
			(thermal_gap 0.1778)
		)
		(pad "B19" thru_hole circle
			(at 8.35025 1.24968 180)
			(size 1.0922 1.0922)
			(drill 0.7366)
			(layers "*.Cu" "*.Mask")
			(remove_unused_layers no)
			(net "PCIE_SAS_CPU_TX_P1")
			(clearance 0.1778)
			(thermal_gap 0.1778)
		)
		(pad "B20" thru_hole circle
			(at 9.34974 3.24993 180)
			(size 1.0922 1.0922)
			(drill 0.7366)
			(layers "*.Cu" "*.Mask")
			(remove_unused_layers no)
			(net "PCIE_SAS_CPU_TX_N1")
			(clearance 0.1778)
			(thermal_gap 0.1778)
		)
		(pad "B21" thru_hole circle
			(at 10.3505 1.24968 180)
			(size 1.0922 1.0922)
			(drill 0.7366)
			(layers "*.Cu" "*.Mask")
			(remove_unused_layers no)
			(net "GND")
			(clearance 0.1778)
			(thermal_gap 0.1778)
		)
		(pad "B22" thru_hole circle
			(at 11.34999 3.24993 180)
			(size 1.0922 1.0922)
			(drill 0.7366)
			(layers "*.Cu" "*.Mask")
			(remove_unused_layers no)
			(net "GND")
			(clearance 0.1778)
			(thermal_gap 0.1778)
		)
		(pad "B23" thru_hole circle
			(at 12.34948 1.24968 180)
			(size 1.0922 1.0922)
			(drill 0.7366)
			(layers "*.Cu" "*.Mask")
			(remove_unused_layers no)
			(net "PCIE_SAS_CPU_TX_P2")
			(clearance 0.1778)
			(thermal_gap 0.1778)
		)
		(pad "B24" thru_hole circle
			(at 13.35024 3.24993 180)
			(size 1.0922 1.0922)
			(drill 0.7366)
			(layers "*.Cu" "*.Mask")
			(remove_unused_layers no)
			(net "PCIE_SAS_CPU_TX_N2")
			(clearance 0.1778)
			(thermal_gap 0.1778)
		)
		(pad "B25" thru_hole circle
			(at 14.34973 1.24968 180)
			(size 1.0922 1.0922)
			(drill 0.7366)
			(layers "*.Cu" "*.Mask")
			(remove_unused_layers no)
			(net "GND")
			(clearance 0.1778)
			(thermal_gap 0.1778)
		)
		(pad "B26" thru_hole circle
			(at 15.35049 3.24993 180)
			(size 1.0922 1.0922)
			(drill 0.7366)
			(layers "*.Cu" "*.Mask")
			(remove_unused_layers no)
			(net "GND")
			(clearance 0.1778)
			(thermal_gap 0.1778)
		)
		(pad "B27" thru_hole circle
			(at 16.34998 1.24968 180)
			(size 1.0922 1.0922)
			(drill 0.7366)
			(layers "*.Cu" "*.Mask")
			(remove_unused_layers no)
			(net "PCIE_SAS_CPU_TX_P3")
			(clearance 0.1778)
			(thermal_gap 0.1778)
		)
		(pad "B28" thru_hole circle
			(at 17.34947 3.24993 180)
			(size 1.0922 1.0922)
			(drill 0.7366)
			(layers "*.Cu" "*.Mask")
			(remove_unused_layers no)
			(net "PCIE_SAS_CPU_TX_N3")
			(clearance 0.1778)
			(thermal_gap 0.1778)
		)
		(pad "B29" thru_hole circle
			(at 18.35023 1.24968 180)
			(size 1.0922 1.0922)
			(drill 0.7366)
			(layers "*.Cu" "*.Mask")
			(remove_unused_layers no)
			(net "GND")
			(clearance 0.1778)
			(thermal_gap 0.1778)
		)
		(pad "B30" thru_hole circle
			(at 19.34972 3.24993 180)
			(size 1.0922 1.0922)
			(drill 0.7366)
			(layers "*.Cu" "*.Mask")
			(remove_unused_layers no)
			(net "GND")
			(clearance 0.1778)
			(thermal_gap 0.1778)
		)
		(pad "B31" thru_hole circle
			(at 20.35048 1.24968 180)
			(size 1.0922 1.0922)
			(drill 0.7366)
			(layers "*.Cu" "*.Mask")
			(remove_unused_layers no)
			(net "TP_MSB_B31_CPU_SATA_TX_P")
			(clearance 0.1778)
			(thermal_gap 0.1778)
		)
		(pad "B32" thru_hole circle
			(at 21.34997 3.24993 180)
			(size 1.0922 1.0922)
			(drill 0.7366)
			(layers "*.Cu" "*.Mask")
			(remove_unused_layers no)
			(net "TP_MSB_B32_CPU_SATA_TX_N")
			(clearance 0.1778)
			(thermal_gap 0.1778)
		)
		(pad "B33" thru_hole circle
			(at 22.34946 1.24968 180)
			(size 1.0922 1.0922)
			(drill 0.7366)
			(layers "*.Cu" "*.Mask")
			(remove_unused_layers no)
			(net "GND")
			(clearance 0.1778)
			(thermal_gap 0.1778)
		)
		(pad "B34" thru_hole circle
			(at 23.35022 3.24993 180)
			(size 1.0922 1.0922)
			(drill 0.7366)
			(layers "*.Cu" "*.Mask")
			(remove_unused_layers no)
			(net "GND")
			(clearance 0.1778)
			(thermal_gap 0.1778)
		)
		(pad "B35" thru_hole circle
			(at 24.34971 1.24968 180)
			(size 1.0922 1.0922)
			(drill 0.7366)
			(layers "*.Cu" "*.Mask")
			(remove_unused_layers no)
			(net "CLK_100M_CLKBUFF_ENET1_DP")
			(clearance 0.1778)
			(thermal_gap 0.1778)
		)
		(pad "B36" thru_hole circle
			(at 25.35047 3.24993 180)
			(size 1.0922 1.0922)
			(drill 0.7366)
			(layers "*.Cu" "*.Mask")
			(remove_unused_layers no)
			(net "CLK_100M_CLKBUFF_ENET1_DN")
			(clearance 0.1778)
			(thermal_gap 0.1778)
		)
		(pad "B37" thru_hole circle
			(at 26.34996 1.24968 180)
			(size 1.0922 1.0922)
			(drill 0.7366)
			(layers "*.Cu" "*.Mask")
			(remove_unused_layers no)
			(net "GND")
			(clearance 0.1778)
			(thermal_gap 0.1778)
		)
		(pad "B38" thru_hole circle
			(at 27.34945 3.24993 180)
			(size 1.0922 1.0922)
			(drill 0.7366)
			(layers "*.Cu" "*.Mask")
			(remove_unused_layers no)
			(net "GND")
			(clearance 0.1778)
			(thermal_gap 0.1778)
		)
		(pad "B39" thru_hole circle
			(at 28.35021 1.24968 180)
			(size 1.0922 1.0922)
			(drill 0.7366)
			(layers "*.Cu" "*.Mask")
			(remove_unused_layers no)
			(net "PMU_PLTRST#")
			(clearance 0.1778)
			(thermal_gap 0.1778)
		)
		(pad "B40" thru_hole circle
			(at 29.3497 3.24993 180)
			(size 1.0922 1.0922)
			(drill 0.7366)
			(layers "*.Cu" "*.Mask")
			(remove_unused_layers no)
			(net "TP_MSB_B40")
			(clearance 0.1778)
			(thermal_gap 0.1778)
		)
		(pad "B41" thru_hole circle
			(at 30.35046 1.24968 180)
			(size 1.0922 1.0922)
			(drill 0.7366)
			(layers "*.Cu" "*.Mask")
			(remove_unused_layers no)
			(net "GND")
			(clearance 0.1778)
			(thermal_gap 0.1778)
		)
		(pad "B42" thru_hole circle
			(at 31.34995 3.24993 180)
			(size 1.0922 1.0922)
			(drill 0.7366)
			(layers "*.Cu" "*.Mask")
			(remove_unused_layers no)
			(net "GND")
			(clearance 0.1778)
			(thermal_gap 0.1778)
		)
		(pad "B43" thru_hole circle
			(at 32.34944 1.24968 180)
			(size 1.0922 1.0922)
			(drill 0.7366)
			(layers "*.Cu" "*.Mask")
			(remove_unused_layers no)
			(net "NIC_SMBUS_SCL")
			(clearance 0.1778)
			(thermal_gap 0.1778)
		)
		(pad "B44" thru_hole circle
			(at 33.3502 3.24993 180)
			(size 1.0922 1.0922)
			(drill 0.7366)
			(layers "*.Cu" "*.Mask")
			(remove_unused_layers no)
			(net "NIC_SMBUS_SDA")
			(clearance 0.1778)
			(thermal_gap 0.1778)
		)
		(pad "B45" thru_hole circle
			(at 34.34969 1.24968 180)
			(size 1.0922 1.0922)
			(drill 0.7366)
			(layers "*.Cu" "*.Mask")
			(remove_unused_layers no)
			(net "GND")
			(clearance 0.1778)
			(thermal_gap 0.1778)
		)
		(pad "B46" thru_hole circle
			(at 35.35045 3.24993 180)
			(size 1.0922 1.0922)
			(drill 0.7366)
			(layers "*.Cu" "*.Mask")
			(remove_unused_layers no)
			(net "GND")
			(clearance 0.1778)
			(thermal_gap 0.1778)
		)
		(pad "B47" thru_hole circle
			(at 36.34994 1.24968 180)
			(size 1.0922 1.0922)
			(drill 0.7366)
			(layers "*.Cu" "*.Mask")
			(remove_unused_layers no)
			(net "TP_MSB_B47_CPU_GBE_TX_P")
			(clearance 0.1778)
			(thermal_gap 0.1778)
		)
		(pad "B48" thru_hole circle
			(at 37.34943 3.24993 180)
			(size 1.0922 1.0922)
			(drill 0.7366)
			(layers "*.Cu" "*.Mask")
			(remove_unused_layers no)
			(net "TP_MSB_B47_CPU_GBE_TX_N")
			(clearance 0.1778)
			(thermal_gap 0.1778)
		)
		(pad "B49" thru_hole circle
			(at 38.35019 1.24968 180)
			(size 1.0922 1.0922)
			(drill 0.7366)
			(layers "*.Cu" "*.Mask")
			(remove_unused_layers no)
			(net "GND")
			(clearance 0.1778)
			(thermal_gap 0.1778)
		)
		(pad "B50" thru_hole circle
			(at 39.34968 3.24993 180)
			(size 1.0922 1.0922)
			(drill 0.7366)
			(layers "*.Cu" "*.Mask")
			(remove_unused_layers no)
			(net "GND")
			(clearance 0.1778)
			(thermal_gap 0.1778)
		)
		(pad "B51" thru_hole circle
			(at 40.35044 1.24968 180)
			(size 1.0922 1.0922)
			(drill 0.7366)
			(layers "*.Cu" "*.Mask")
			(remove_unused_layers no)
			(net "PCIE_SAS_CPU_TX_P4")
			(clearance 0.1778)
			(thermal_gap 0.1778)
		)
		(pad "B52" thru_hole circle
			(at 41.34993 3.24993 180)
			(size 1.0922 1.0922)
			(drill 0.7366)
			(layers "*.Cu" "*.Mask")
			(remove_unused_layers no)
			(net "PCIE_SAS_CPU_TX_N4")
			(clearance 0.1778)
			(thermal_gap 0.1778)
		)
		(pad "B53" thru_hole circle
			(at 42.34942 1.24968 180)
			(size 1.0922 1.0922)
			(drill 0.7366)
			(layers "*.Cu" "*.Mask")
			(remove_unused_layers no)
			(net "GND")
			(clearance 0.1778)
			(thermal_gap 0.1778)
		)
		(pad "B54" thru_hole circle
			(at 43.35018 3.24993 180)
			(size 1.0922 1.0922)
			(drill 0.7366)
			(layers "*.Cu" "*.Mask")
			(remove_unused_layers no)
			(net "GND")
			(clearance 0.1778)
			(thermal_gap 0.1778)
		)
		(pad "B55" thru_hole circle
			(at 44.34967 1.24968 180)
			(size 1.0922 1.0922)
			(drill 0.7366)
			(layers "*.Cu" "*.Mask")
			(remove_unused_layers no)
			(net "PCIE_SAS_CPU_TX_P5")
			(clearance 0.1778)
			(thermal_gap 0.1778)
		)
		(pad "B56" thru_hole circle
			(at 45.35043 3.24993 180)
			(size 1.0922 1.0922)
			(drill 0.7366)
			(layers "*.Cu" "*.Mask")
			(remove_unused_layers no)
			(net "PCIE_SAS_CPU_TX_N5")
			(clearance 0.1778)
			(thermal_gap 0.1778)
		)
		(pad "B57" thru_hole circle
			(at 46.34992 1.24968 180)
			(size 1.0922 1.0922)
			(drill 0.7366)
			(layers "*.Cu" "*.Mask")
			(remove_unused_layers no)
			(net "GND")
			(clearance 0.1778)
			(thermal_gap 0.1778)
		)
		(pad "B58" thru_hole circle
			(at 47.34941 3.24993 180)
			(size 1.0922 1.0922)
			(drill 0.7366)
			(layers "*.Cu" "*.Mask")
			(remove_unused_layers no)
			(net "GND")
			(clearance 0.1778)
			(thermal_gap 0.1778)
		)
		(pad "B59" thru_hole circle
			(at 48.35017 1.24968 180)
			(size 1.0922 1.0922)
			(drill 0.7366)
			(layers "*.Cu" "*.Mask")
			(remove_unused_layers no)
			(net "PCIE_SAS_CPU_TX_P6")
			(clearance 0.1778)
			(thermal_gap 0.1778)
		)
		(pad "B60" thru_hole circle
			(at 49.34966 3.24993 180)
			(size 1.0922 1.0922)
			(drill 0.7366)
			(layers "*.Cu" "*.Mask")
			(remove_unused_layers no)
			(net "PCIE_SAS_CPU_TX_N6")
			(clearance 0.1778)
			(thermal_gap 0.1778)
		)
		(pad "B61" thru_hole circle
			(at 50.35042 1.24968 180)
			(size 1.0922 1.0922)
			(drill 0.7366)
			(layers "*.Cu" "*.Mask")
			(remove_unused_layers no)
			(net "GND")
			(clearance 0.1778)
			(thermal_gap 0.1778)
		)
		(pad "B62" thru_hole circle
			(at 51.34991 3.24993 180)
			(size 1.0922 1.0922)
			(drill 0.7366)
			(layers "*.Cu" "*.Mask")
			(remove_unused_layers no)
			(net "GND")
			(clearance 0.1778)
			(thermal_gap 0.1778)
		)
		(pad "B63" thru_hole circle
			(at 52.3494 1.24968 180)
			(size 1.0922 1.0922)
			(drill 0.7366)
			(layers "*.Cu" "*.Mask")
			(remove_unused_layers no)
			(net "PCIE_SAS_CPU_TX_P7")
			(clearance 0.1778)
			(thermal_gap 0.1778)
		)
		(pad "B64" thru_hole circle
			(at 53.35016 3.24993 180)
			(size 1.0922 1.0922)
			(drill 0.7366)
			(layers "*.Cu" "*.Mask")
			(remove_unused_layers no)
			(net "PCIE_SAS_CPU_TX_N7")
			(clearance 0.1778)
			(thermal_gap 0.1778)
		)
		(pad "B65" thru_hole circle
			(at 54.34965 1.24968 180)
			(size 1.0922 1.0922)
			(drill 0.7366)
			(layers "*.Cu" "*.Mask")
			(remove_unused_layers no)
			(net "GND")
			(clearance 0.1778)
			(thermal_gap 0.1778)
		)
		(pad "B66" thru_hole circle
			(at 55.35041 3.24993 180)
			(size 1.0922 1.0922)
			(drill 0.7366)
			(layers "*.Cu" "*.Mask")
			(remove_unused_layers no)
			(net "GND")
			(clearance 0.1778)
			(thermal_gap 0.1778)
		)
	)
)
